FILE_TYPE=LIBRARY_PARTS;
primitive 'NCT7718W';
  pin
    'VDD':
      PIN_NUMBER='(1)';
      PINUSE='POWER';
      NO_LOAD_CHECK='Both';
      NO_IO_CHECK='Both';
      NO_ASSERT_CHECK='TRUE';
      NO_DIR_CHECK='TRUE';
      ALLOW_CONNECT='TRUE';
    'D+':
      PIN_NUMBER='(2)';
      INPUT_LOAD='(-0.01,0.01)';
    'D-':
      PIN_NUMBER='(3)';
      INPUT_LOAD='(-0.01,0.01)';
    'T_CRIT#':
      PIN_NUMBER='(4)';
      OUTPUT_TYPE='(OC,AND)';
      OUTPUT_LOAD='(1.0,*)';
    'GND':
      PIN_NUMBER='(5)';
      PINUSE='POWER';
      NO_LOAD_CHECK='Both';
      NO_IO_CHECK='Both';
      NO_ASSERT_CHECK='TRUE';
      NO_DIR_CHECK='TRUE';
      ALLOW_CONNECT='TRUE';
    'ALERT#':
      PIN_NUMBER='(6)';
      OUTPUT_TYPE='(OC,AND)';
      OUTPUT_LOAD='(1.0,*)';
    'SDA':
      PIN_NUMBER='(7)';
      BIDIRECTIONAL='TRUE';
      INPUT_LOAD='(-0.01,0.01)';
      OUTPUT_LOAD='(1.0,-1.0)';
    'SCL':
      PIN_NUMBER='(8)';
      INPUT_LOAD='(-0.01,0.01)';
  end_pin;
  body
    PART_NAME='NCT7718W';
    BODY_NAME='NCT7718W';
    PHYS_DES_PREFIX='U';
    CLASS='IC';
  end_body;
end_primitive;

END.
